# BASEBOARD_FAB2 (Tioga Pass) — schematic netlist excerpt (pin names and nets, part order shuffled) for the footprints in the layout excerpt that follows; sources: Cadence DE-HDL packaged netlist, KiCad conversion of Wiwynn_Tioga_Pass_MB.brd

C7E4  CAP_A  0.1UF 16V 10% X7R  pkg 0402V  page 95 : A = P3V3_STBY ; B = GND
C2M18  CAP_A  1.0UF 6.3V 10% X6S  pkg 0402V  page 131 : A = P1V05_PCH_STBY ; B = GND
C3P15  CAP  0.22UF 16V 10% X7R  pkg 0402  page 107 : A = P3E_CPU0_PE1_SS_TXP<1> ; B = P3E_CPU0_PE1_PCH_TXP<1>

(kicad_pcb
	(version 20260206)
	(generator "pcbnew")
	(generator_version "10.0")
	(general
		(thickness 1.6)
		(legacy_teardrops no)
	)
	(paper "A4")
	(title_block
		(title "Wiwynn_Tioga_Pass_MB.brd")
		(comment 1 "Tioga Pass / footprints 4200-4202 of 4770")
	)
	(layers
		(0 "F.Cu" signal "TOP")
		(4 "In1.Cu" signal "L2GND")
		(6 "In2.Cu" signal "L3")
		(8 "In3.Cu" signal "L4GND")
		(10 "In4.Cu" signal "L5")
		(12 "In5.Cu" signal "L6GND")
		(14 "In6.Cu" signal "L7VCC")
		(16 "In7.Cu" signal "L8VCC")
		(18 "In8.Cu" signal "L9GND")
		(20 "In9.Cu" signal "L10")
		(22 "In10.Cu" signal "L11GND")
		(24 "In11.Cu" signal "L12")
		(26 "In12.Cu" signal "L13GND")
		(2 "B.Cu" signal "BOTTOM")
		(9 "F.Adhes" user "F.Adhesive")
		(11 "B.Adhes" user "B.Adhesive")
		(13 "F.Paste" user "Package Geometry/Pastemask Top")
		(15 "B.Paste" user "Package Geometry/Pastemask Bottom")
		(5 "F.SilkS" user "Ref Des/Silkscreen Top")
		(7 "B.SilkS" user "Ref Des/Silkscreen Bottom")
		(1 "F.Mask" user "Board Geometry/Soldermask Top")
		(3 "B.Mask" user "Board Geometry/Soldermask Bottom")
		(17 "Dwgs.User" user "User.Drawings")
		(19 "Cmts.User" user "User.Comments")
		(21 "Eco1.User" user "User.Eco1")
		(23 "Eco2.User" user "User.Eco2")
		(25 "Edge.Cuts" user "Board Geometry/Outline")
		(27 "Margin" user)
		(31 "F.CrtYd" user "Package Geometry/Place Bound Top")
		(29 "B.CrtYd" user "Package Geometry/Place Bound Bottom")
		(35 "F.Fab" user "Ref Des/Assembly Top")
		(33 "B.Fab" user "Ref Des/Assembly Bottom")
	)
	(footprint ""
		(layer "B.Cu")
		(at 341.666068 -77.694536 180)
		(property "Reference" "C3P15"
			(at 0 0 0)
			(layer "B.SilkS")
			(hide yes)
			(effects
				(font
					(size 1.27 1.27)
				)
				(justify mirror)
			)
		)
		(property "Value" ""
			(at 0 0 0)
			(layer "B.Fab")
			(effects
				(font
					(size 1.27 1.27)
				)
				(justify mirror)
			)
		)
		(duplicate_pad_numbers_are_jumpers no)
		(fp_poly
			(pts
				(xy -0.3048 -0.1016) (xy -0.3048 0.9906) (xy 0.3048 0.9906) (xy 0.3048 -0.1016)
			)
			(stroke
				(width 0)
				(type default)
			)
			(fill no)
			(layer "B.CrtYd")
		)
		(fp_line
			(start 0.3048 0.9906)
			(end -0.3048 0.9906)
			(stroke
				(width 0.1)
				(type default)
			)
			(layer "B.Fab")
		)
		(fp_line
			(start 0.3048 -0.1016)
			(end 0.3048 0.9906)
			(stroke
				(width 0.1)
				(type default)
			)
			(layer "B.Fab")
		)
		(fp_line
			(start -0.3048 0.9906)
			(end -0.3048 -0.1016)
			(stroke
				(width 0.1)
				(type default)
			)
			(layer "B.Fab")
		)
		(fp_line
			(start -0.3048 -0.1016)
			(end 0.3048 -0.1016)
			(stroke
				(width 0.1)
				(type default)
			)
			(layer "B.Fab")
		)
		(pad "1" smd rect
			(at 0 0)
			(size 0.508 0.508)
			(layers "B.Cu" "B.Mask" "B.Paste")
			(net "P3E_CPU0_PE1_SS_TXP<1>")
		)
		(pad "2" smd rect
			(at 0 0.889)
			(size 0.508 0.508)
			(layers "B.Cu" "B.Mask" "B.Paste")
			(net "P3E_CPU0_PE1_PCH_TXP<1>")
		)
		(zone
			(layer "B.Cu")
			(hatch none 0.5)
			(connect_pads
				(clearance 0)
			)
			(min_thickness 0.25)
			(keepout
				(tracks not_allowed)
				(vias allowed)
				(pads allowed)
				(copperpour not_allowed)
				(footprints allowed)
			)
			(placement
				(enabled no)
				(sheetname "")
			)
			(fill
				(thermal_gap 0.5)
				(thermal_bridge_width 0.5)
				(island_removal_mode 0)
			)
			(polygon
				(pts
					(xy 341.412068 -78.329536) (xy 341.920068 -78.329536) (xy 341.920068 -77.948536) (xy 341.412068 -77.948536)
				)
			)
		)
		(zone
			(layer "B.Cu")
			(hatch none 0.5)
			(connect_pads
				(clearance 0)
			)
			(min_thickness 0.25)
			(keepout
				(tracks allowed)
				(vias not_allowed)
				(pads allowed)
				(copperpour not_allowed)
				(footprints allowed)
			)
			(placement
				(enabled no)
				(sheetname "")
			)
			(fill
				(thermal_gap 0.5)
				(thermal_bridge_width 0.5)
				(island_removal_mode 0)
			)
			(polygon
				(pts
					(xy 341.412068 -77.948536) (xy 341.920068 -77.948536) (xy 341.920068 -78.329536) (xy 341.412068 -78.329536)
				)
			)
		)
	)
	(footprint ""
		(layer "B.Cu")
		(at 379.3998 -46.2026 180)
		(property "Reference" "C7E4"
			(at 0 0 0)
			(layer "B.SilkS")
			(hide yes)
			(effects
				(font
					(size 1.27 1.27)
				)
				(justify mirror)
			)
		)
		(property "Value" ""
			(at 0 0 0)
			(layer "B.Fab")
			(effects
				(font
					(size 1.27 1.27)
				)
				(justify mirror)
			)
		)
		(duplicate_pad_numbers_are_jumpers no)
		(fp_poly
			(pts
				(xy -0.3048 -0.1016) (xy -0.3048 0.9906) (xy 0.3048 0.9906) (xy 0.3048 -0.1016)
			)
			(stroke
				(width 0)
				(type default)
			)
			(fill no)
			(layer "B.CrtYd")
		)
		(fp_line
			(start 0.3048 0.9906)
			(end -0.3048 0.9906)
			(stroke
				(width 0.1)
				(type default)
			)
			(layer "B.Fab")
		)
		(fp_line
			(start 0.3048 -0.1016)
			(end 0.3048 0.9906)
			(stroke
				(width 0.1)
				(type default)
			)
			(layer "B.Fab")
		)
		(fp_line
			(start -0.3048 0.9906)
			(end -0.3048 -0.1016)
			(stroke
				(width 0.1)
				(type default)
			)
			(layer "B.Fab")
		)
		(fp_line
			(start -0.3048 -0.1016)
			(end 0.3048 -0.1016)
			(stroke
				(width 0.1)
				(type default)
			)
			(layer "B.Fab")
		)
		(pad "1" smd rect
			(at 0 0)
			(size 0.508 0.508)
			(layers "B.Cu" "B.Mask" "B.Paste")
			(net "P3V3_STBY")
		)
		(pad "2" smd rect
			(at 0 0.889)
			(size 0.508 0.508)
			(layers "B.Cu" "B.Mask" "B.Paste")
			(net "GND")
		)
		(zone
			(layer "B.Cu")
			(hatch none 0.5)
			(connect_pads
				(clearance 0)
			)
			(min_thickness 0.25)
			(keepout
				(tracks not_allowed)
				(vias allowed)
				(pads allowed)
				(copperpour not_allowed)
				(footprints allowed)
			)
			(placement
				(enabled no)
				(sheetname "")
			)
			(fill
				(thermal_gap 0.5)
				(thermal_bridge_width 0.5)
				(island_removal_mode 0)
			)
			(polygon
				(pts
					(xy 379.1458 -46.8376) (xy 379.6538 -46.8376) (xy 379.6538 -46.4566) (xy 379.1458 -46.4566)
				)
			)
		)
		(zone
			(layer "B.Cu")
			(hatch none 0.5)
			(connect_pads
				(clearance 0)
			)
			(min_thickness 0.25)
			(keepout
				(tracks allowed)
				(vias not_allowed)
				(pads allowed)
				(copperpour not_allowed)
				(footprints allowed)
			)
			(placement
				(enabled no)
				(sheetname "")
			)
			(fill
				(thermal_gap 0.5)
				(thermal_bridge_width 0.5)
				(island_removal_mode 0)
			)
			(polygon
				(pts
					(xy 379.1458 -46.4566) (xy 379.6538 -46.4566) (xy 379.6538 -46.8376) (xy 379.1458 -46.8376)
				)
			)
		)
	)
	(footprint ""
		(layer "B.Cu")
		(at 390.93775 -114.25555 180)
		(property "Reference" "C2M18"
			(at 0 0 0)
			(layer "B.SilkS")
			(hide yes)
			(effects
				(font
					(size 1.27 1.27)
				)
				(justify mirror)
			)
		)
		(property "Value" ""
			(at 0 0 0)
			(layer "B.Fab")
			(effects
				(font
					(size 1.27 1.27)
				)
				(justify mirror)
			)
		)
		(duplicate_pad_numbers_are_jumpers no)
		(fp_rect
			(start 0.2794 0.9144)
			(end -0.2794 -0.1143)
			(stroke
				(width 0)
				(type default)
			)
			(fill no)
			(layer "B.CrtYd")
		)
		(fp_line
			(start 0.2794 0.9144)
			(end 0.2794 -0.1143)
			(stroke
				(width 0.1)
				(type default)
			)
			(layer "B.Fab")
		)
		(fp_line
			(start 0.2794 -0.1143)
			(end -0.2794 -0.1143)
			(stroke
				(width 0.1)
				(type default)
			)
			(layer "B.Fab")
		)
		(fp_line
			(start -0.2794 0.9144)
			(end 0.2794 0.9144)
			(stroke
				(width 0.1)
				(type default)
			)
			(layer "B.Fab")
		)
		(fp_line
			(start -0.2794 -0.1143)
			(end -0.2794 0.9144)
			(stroke
				(width 0.1)
				(type default)
			)
			(layer "B.Fab")
		)
		(pad "1" smd custom
			(at 0 0 90)
			(size 0.10414 0.10414)
			(layers "B.Cu" "B.Mask" "B.Paste")
			(net "P1V05_PCH_STBY")
			(options
				(clearance outline)
				(anchor circle)
			)
			(primitives
				(gr_poly
					(pts
						(xy -0.20828 -0.08636) (xy -0.20828 0.08636) (xy -0.08636 0.20828) (xy 0.086614 0.20828) (xy 0.20828 0.086614)
						(xy 0.20828 -0.08636) (xy 0.08636 -0.20828) (xy -0.08636 -0.20828)
					)
					(width 0)
					(fill yes)
				)
			)
		)
		(pad "2" smd custom
			(at 0 0.8001 90)
			(size 0.10414 0.10414)
			(layers "B.Cu" "B.Mask" "B.Paste")
			(net "GND")
			(options
				(clearance outline)
				(anchor circle)
			)
			(primitives
				(gr_poly
					(pts
						(xy -0.20828 -0.08636) (xy -0.20828 0.08636) (xy -0.08636 0.20828) (xy 0.086614 0.20828) (xy 0.20828 0.086614)
						(xy 0.20828 -0.08636) (xy 0.08636 -0.20828) (xy -0.08636 -0.20828)
					)
					(width 0)
					(fill yes)
				)
			)
		)
		(zone
			(layer "B.Cu")
			(hatch none 0.5)
			(connect_pads
				(clearance 0)
			)
			(min_thickness 0.25)
			(keepout
				(tracks not_allowed)
				(vias allowed)
				(pads allowed)
				(copperpour not_allowed)
				(footprints allowed)
			)
			(placement
				(enabled no)
				(sheetname "")
			)
			(fill
				(thermal_gap 0.5)
				(thermal_bridge_width 0.5)
				(island_removal_mode 0)
			)
			(polygon
				(pts
					(xy 390.85012 -114.4651) (xy 390.85012 -114.8461) (xy 391.02538 -114.8461) (xy 391.025634 -114.4651)
				)
			)
		)
		(zone
			(layer "B.Cu")
			(hatch none 0.5)
			(connect_pads
				(clearance 0)
			)
			(min_thickness 0.25)
			(keepout
				(tracks allowed)
				(vias not_allowed)
				(pads allowed)
				(copperpour not_allowed)
				(footprints allowed)
			)
			(placement
				(enabled no)
				(sheetname "")
			)
			(fill
				(thermal_gap 0.5)
				(thermal_bridge_width 0.5)
				(island_removal_mode 0)
			)
			(polygon
				(pts
					(xy 390.85012 -114.4651) (xy 390.85012 -114.8461) (xy 391.02538 -114.8461) (xy 391.025634 -114.4651)
				)
			)
		)
	)
)
